(kicad_pcb
	(version 20241229)
	(generator "pcbnew")
	(generator_version "9.0")
	(general
		(thickness 1.711)
		(legacy_teardrops no)
	)
	(paper "A4")
	(title_block
		(title "Antmicro Baseboard for Jetson AGX Thor")
		(date "2026-02-18")
		(rev "1.1.0")
		(company "Antmicro Ltd")
		(comment 1 "www.antmicro.com")
		(comment 9 "footprints 444-447 of 1170")
	)
	(layers
		(0 "F.Cu" signal)
		(4 "In1.Cu" signal)
		(6 "In2.Cu" signal)
		(8 "In3.Cu" signal)
		(10 "In4.Cu" jumper)
		(12 "In5.Cu" signal)
		(14 "In6.Cu" signal)
		(16 "In7.Cu" signal)
		(18 "In8.Cu" signal)
		(2 "B.Cu" signal)
		(9 "F.Adhes" user "F.Adhesive")
		(11 "B.Adhes" user "B.Adhesive")
		(13 "F.Paste" user)
		(15 "B.Paste" user)
		(5 "F.SilkS" user "F.Silkscreen")
		(7 "B.SilkS" user "B.Silkscreen")
		(1 "F.Mask" user)
		(3 "B.Mask" user)
		(17 "Dwgs.User" user "User.Drawings")
		(19 "Cmts.User" user "User.Comments")
		(21 "Eco1.User" user "User.Eco1")
		(23 "Eco2.User" user "User.Eco2")
		(25 "Edge.Cuts" user)
		(27 "Margin" user)
		(31 "F.CrtYd" user "F.Courtyard")
		(29 "B.CrtYd" user "B.Courtyard")
		(35 "F.Fab" user)
		(33 "B.Fab" user)
	)
	(footprint "antmicro-footprints:LED_0603_1608Metric_G"
		(layer "F.Cu")
		(at 235.540532 82.71 180)
		(descr "LED SMD 0603 Green")
		(tags "LED SMD 0603 Green")
		(property "Reference" "D24"
			(at -1.059468 -0.799999 0)
			(layer "F.SilkS")
			(effects
				(font
					(size 0.7 0.7)
					(thickness 0.15)
				)
				(justify right top)
			)
		)
		(property "Value" "LED_G_0603_LTST-C190GKT"
			(at -0.001 1.599 0)
			(layer "F.Fab")
			(effects
				(font
					(size 0.7 0.7)
					(thickness 0.15)
				)
				(justify right top)
			)
		)
		(property "Datasheet" "https://media.digikey.com/pdf/Data%20Sheets/Lite-On%20PDFs/LTST-C190GKT.pdf"
			(at 0 0 0)
			(layer "F.Fab")
			(hide yes)
			(effects
				(font
					(size 1.27 1.27)
					(thickness 0.15)
				)
			)
		)
		(property "Description" "LED, Green, SMD, 0603, 20 mA, 2.1 V, 569 nm"
			(at 0 0 0)
			(layer "F.Fab")
			(hide yes)
			(effects
				(font
					(size 1.27 1.27)
					(thickness 0.15)
				)
			)
		)
		(property "MPN" "LTST-C190GKT"
			(at 0 0 180)
			(unlocked yes)
			(layer "F.Fab")
			(hide yes)
			(effects
				(font
					(size 1 1)
					(thickness 0.15)
				)
			)
		)
		(property "Manufacturer" "Lite-On"
			(at 0 0 180)
			(unlocked yes)
			(layer "F.Fab")
			(hide yes)
			(effects
				(font
					(size 1 1)
					(thickness 0.15)
				)
			)
		)
		(property "Author" "Antmicro"
			(at 0 0 180)
			(unlocked yes)
			(layer "F.Fab")
			(hide yes)
			(effects
				(font
					(size 1 1)
					(thickness 0.15)
				)
			)
		)
		(property "License" "Apache-2.0"
			(at 0 0 180)
			(unlocked yes)
			(layer "F.Fab")
			(hide yes)
			(effects
				(font
					(size 1 1)
					(thickness 0.15)
				)
			)
		)
		(property "Color" "Green"
			(at 0 0 180)
			(unlocked yes)
			(layer "F.Fab")
			(hide yes)
			(effects
				(font
					(size 1 1)
					(thickness 0.15)
				)
			)
		)
		(sheetname "/USB Debug, PD/")
		(sheetfile "usb_debug_pd.kicad_sch")
		(attr smd)
		(fp_line
			(start 0.22 0.35)
			(end -0.22 0.35)
			(stroke
				(width 0.15)
				(type solid)
			)
			(layer "F.SilkS")
		)
		(fp_line
			(start 0.22 -0.35)
			(end -0.22 -0.35)
			(stroke
				(width 0.15)
				(type solid)
			)
			(layer "F.SilkS")
		)
		(fp_line
			(start 0.105328 0.201008)
			(end 0.105329 -0.198992)
			(stroke
				(width 0.1)
				(type solid)
			)
			(layer "F.SilkS")
		)
		(fp_line
			(start 0.105328 0.201008)
			(end -0.094672 0.001008)
			(stroke
				(width 0.1)
				(type solid)
			)
			(layer "F.SilkS")
		)
		(fp_line
			(start 0.105328 0.001008)
			(end 0.240001 0.001)
			(stroke
				(width 0.1)
				(type solid)
			)
			(layer "F.SilkS")
		)
		(fp_line
			(start -0.094672 0.201008)
			(end -0.094672 -0.198992)
			(stroke
				(width 0.1)
				(type solid)
			)
			(layer "F.SilkS")
		)
		(fp_line
			(start -0.094672 0.001008)
			(end 0.105329 -0.198992)
			(stroke
				(width 0.1)
				(type solid)
			)
			(layer "F.SilkS")
		)
		(fp_line
			(start -0.094672 0.001008)
			(end -0.24 0.001008)
			(stroke
				(width 0.1)
				(type solid)
			)
			(layer "F.SilkS")
		)
		(fp_line
			(start -1.18 -0.319)
			(end -1.18 0.321)
			(stroke
				(width 0.15)
				(type solid)
			)
			(layer "F.SilkS")
		)
		(fp_poly
			(pts
				(xy 1.25 0.65) (xy -1.25 0.65) (xy -1.25 -0.65) (xy 1.25 -0.65)
			)
			(stroke
				(width 0.05)
				(type solid)
			)
			(fill no)
			(layer "F.CrtYd")
		)
		(fp_line
			(start 0.599 0)
			(end 0.200999 0)
			(stroke
				(width 0.15)
				(type solid)
			)
			(layer "F.Fab")
		)
		(fp_line
			(start 0.201 0.2)
			(end 0.200999 0)
			(stroke
				(width 0.15)
				(type solid)
			)
			(layer "F.Fab")
		)
		(fp_line
			(start 0.201 -0.202)
			(end -0.101 0)
			(stroke
				(width 0.15)
				(type solid)
			)
			(layer "F.Fab")
		)
		(fp_line
			(start 0.200999 0)
			(end 0.201 -0.202)
			(stroke
				(width 0.15)
				(type solid)
			)
			(layer "F.Fab")
		)
		(fp_line
			(start -0.101 0)
			(end 0.201 0.2)
			(stroke
				(width 0.15)
				(type solid)
			)
			(layer "F.Fab")
		)
		(fp_line
			(start -0.199 0.2)
			(end -0.199 0.1)
			(stroke
				(width 0.15)
				(type solid)
			)
			(layer "F.Fab")
		)
		(fp_line
			(start -0.199 0)
			(end -0.597 0)
			(stroke
				(width 0.15)
				(type solid)
			)
			(layer "F.Fab")
		)
		(fp_line
			(start -0.199 -0.202)
			(end -0.199 0.1)
			(stroke
				(width 0.15)
				(type solid)
			)
			(layer "F.Fab")
		)
		(fp_poly
			(pts
				(xy 0.848 0.4) (xy -0.85 0.4) (xy -0.85 -0.402) (xy 0.848 -0.401999)
			)
			(stroke
				(width 0.15)
				(type solid)
			)
			(fill no)
			(layer "F.Fab")
		)
		(fp_text user "Author: Antmicro"
			(at -1.4224 4.799 0)
			(layer "F.Fab")
			(effects
				(font
					(size 0.7 0.7)
					(thickness 0.15)
				)
				(justify right top)
			)
		)
		(fp_text user "License: Apache-2.0"
			(at -1.4224 3.599 0)
			(layer "F.Fab")
			(effects
				(font
					(size 0.7 0.7)
					(thickness 0.15)
				)
				(justify right top)
			)
		)
		(fp_text user "${REFERENCE}"
			(at -1.4224 5.999 0)
			(layer "F.Fab")
			(effects
				(font
					(size 0.7 0.7)
					(thickness 0.15)
				)
				(justify right top)
			)
		)
		(pad "1" smd roundrect
			(at -0.7 0)
			(size 0.8 1)
			(layers "F.Cu" "F.Mask" "F.Paste")
			(roundrect_rratio 0.2)
			(net 1 "GND")
			(pinfunction "C")
			(pintype "passive")
		)
		(pad "2" smd roundrect
			(at 0.7 0)
			(size 0.8 1)
			(layers "F.Cu" "F.Mask" "F.Paste")
			(roundrect_rratio 0.2)
			(net 1387 "Net-(D24-A)")
			(pinfunction "A")
			(pintype "passive")
		)
	)
	(footprint "antmicro-footprints:R_0402_1005Metric"
		(layer "F.Cu")
		(at 208.1 64.22 90)
		(descr "Resistor SMD 0402")
		(tags "resistor SMD 0402")
		(property "Reference" "R409"
			(at -0.98 -3.2 180)
			(layer "F.SilkS")
			(effects
				(font
					(size 0.7 0.7)
					(thickness 0.15)
				)
				(justify left bottom)
			)
		)
		(property "Value" "R_232k_0402"
			(at -1.011843 1.772047 90)
			(layer "F.Fab")
			(effects
				(font
					(size 0.7 0.7)
					(thickness 0.15)
				)
				(justify left bottom)
			)
		)
		(property "Datasheet" "https://www.mouser.com/datasheet/2/447/PYu_RT_1_to_0_01_RoHS_L_12-3003070.pdf"
			(at 0 0 90)
			(layer "F.Fab")
			(hide yes)
			(effects
				(font
					(size 1.27 1.27)
					(thickness 0.15)
				)
			)
		)
		(property "Description" "SMD Chip Resistor"
			(at 0 0 90)
			(layer "F.Fab")
			(hide yes)
			(effects
				(font
					(size 1.27 1.27)
					(thickness 0.15)
				)
			)
		)
		(property "MPN" "RT0402FRE07232KL"
			(at 0 0 90)
			(unlocked yes)
			(layer "F.Fab")
			(hide yes)
			(effects
				(font
					(size 1 1)
					(thickness 0.15)
				)
			)
		)
		(property "Manufacturer" "YAGEO"
			(at 0 0 90)
			(unlocked yes)
			(layer "F.Fab")
			(hide yes)
			(effects
				(font
					(size 1 1)
					(thickness 0.15)
				)
			)
		)
		(property "License" "Apache-2.0"
			(at 0 0 90)
			(unlocked yes)
			(layer "F.Fab")
			(hide yes)
			(effects
				(font
					(size 1 1)
					(thickness 0.15)
				)
			)
		)
		(property "Author" "Antmicro"
			(at 0 0 90)
			(unlocked yes)
			(layer "F.Fab")
			(hide yes)
			(effects
				(font
					(size 1 1)
					(thickness 0.15)
				)
			)
		)
		(property "Val" "232k"
			(at 0 0 90)
			(unlocked yes)
			(layer "F.Fab")
			(hide yes)
			(effects
				(font
					(size 1 1)
					(thickness 0.15)
				)
			)
		)
		(property "Tolerance" "1%"
			(at 0 0 90)
			(unlocked yes)
			(layer "F.Fab")
			(hide yes)
			(effects
				(font
					(size 1 1)
					(thickness 0.15)
				)
			)
		)
		(sheetname "/Power/")
		(sheetfile "power.kicad_sch")
		(attr smd)
		(fp_rect
			(start -0.925 -0.47)
			(end 0.925 0.47)
			(stroke
				(width 0.05)
				(type default)
			)
			(fill no)
			(layer "F.CrtYd")
		)
		(fp_rect
			(start -0.5 -0.25)
			(end 0.5 0.25)
			(stroke
				(width 0.15)
				(type solid)
			)
			(fill no)
			(layer "F.Fab")
		)
		(fp_text user "Author: Antmicro"
			(at -0.95 4.169 90)
			(layer "F.Fab")
			(effects
				(font
					(size 0.7 0.7)
					(thickness 0.15)
				)
				(justify left bottom)
			)
		)
		(fp_text user "License: Apache-2.0"
			(at -0.95 5.169 90)
			(layer "F.Fab")
			(effects
				(font
					(size 0.7 0.7)
					(thickness 0.15)
				)
				(justify left bottom)
			)
		)
		(fp_text user "${REFERENCE}"
			(at -0.95 3.168 90)
			(layer "F.Fab")
			(effects
				(font
					(size 0.7 0.7)
					(thickness 0.15)
				)
				(justify left bottom)
			)
		)
		(pad "1" smd roundrect
			(at -0.48 0 90)
			(size 0.59 0.64)
			(layers "F.Cu" "F.Mask" "F.Paste")
			(roundrect_rratio 0.25)
			(net 1386 "Net-(U9-SET)")
			(pintype "passive")
		)
		(pad "2" smd roundrect
			(at 0.48 0 90)
			(size 0.59 0.64)
			(layers "F.Cu" "F.Mask" "F.Paste")
			(roundrect_rratio 0.25)
			(net 1383 "VCC_NO_OVP")
			(pintype "passive")
		)
	)
	(footprint "antmicro-footprints:LED_0603_1608Metric_G"
		(layer "F.Cu")
		(at 161.74 55.3 -90)
		(descr "LED SMD 0603 Green")
		(tags "LED SMD 0603 Green")
		(property "Reference" "D40"
			(at -0.89 1.44 90)
			(layer "F.SilkS")
			(effects
				(font
					(size 0.7 0.7)
					(thickness 0.15)
				)
				(justify right top)
			)
		)
		(property "Value" "LED_G_0603_LTST-C190GKT"
			(at -0.001 1.599 90)
			(layer "F.Fab")
			(effects
				(font
					(size 0.7 0.7)
					(thickness 0.15)
				)
				(justify right top)
			)
		)
		(property "Datasheet" "https://media.digikey.com/pdf/Data%20Sheets/Lite-On%20PDFs/LTST-C190GKT.pdf"
			(at 0 0 90)
			(layer "F.Fab")
			(hide yes)
			(effects
				(font
					(size 1.27 1.27)
					(thickness 0.15)
				)
			)
		)
		(property "Description" "LED, Green, SMD, 0603, 20 mA, 2.1 V, 569 nm"
			(at 0 0 90)
			(layer "F.Fab")
			(hide yes)
			(effects
				(font
					(size 1.27 1.27)
					(thickness 0.15)
				)
			)
		)
		(property "MPN" "LTST-C190GKT"
			(at 0 0 270)
			(unlocked yes)
			(layer "F.Fab")
			(hide yes)
			(effects
				(font
					(size 1 1)
					(thickness 0.15)
				)
			)
		)
		(property "Manufacturer" "Lite-On"
			(at 0 0 270)
			(unlocked yes)
			(layer "F.Fab")
			(hide yes)
			(effects
				(font
					(size 1 1)
					(thickness 0.15)
				)
			)
		)
		(property "Author" "Antmicro"
			(at 0 0 270)
			(unlocked yes)
			(layer "F.Fab")
			(hide yes)
			(effects
				(font
					(size 1 1)
					(thickness 0.15)
				)
			)
		)
		(property "License" "Apache-2.0"
			(at 0 0 270)
			(unlocked yes)
			(layer "F.Fab")
			(hide yes)
			(effects
				(font
					(size 1 1)
					(thickness 0.15)
				)
			)
		)
		(property "Color" "Green"
			(at 0 0 270)
			(unlocked yes)
			(layer "F.Fab")
			(hide yes)
			(effects
				(font
					(size 1 1)
					(thickness 0.15)
				)
			)
		)
		(sheetname "/Power/")
		(sheetfile "power.kicad_sch")
		(attr smd)
		(fp_line
			(start 0.22 0.35)
			(end -0.22 0.35)
			(stroke
				(width 0.15)
				(type solid)
			)
			(layer "F.SilkS")
		)
		(fp_line
			(start -0.094672 0.201008)
			(end -0.094672 -0.198992)
			(stroke
				(width 0.1)
				(type solid)
			)
			(layer "F.SilkS")
		)
		(fp_line
			(start 0.105328 0.201008)
			(end -0.094672 0.001008)
			(stroke
				(width 0.1)
				(type solid)
			)
			(layer "F.SilkS")
		)
		(fp_line
			(start 0.105328 0.201008)
			(end 0.105328 -0.198992)
			(stroke
				(width 0.1)
				(type solid)
			)
			(layer "F.SilkS")
		)
		(fp_line
			(start -0.094672 0.001008)
			(end -0.24 0.001008)
			(stroke
				(width 0.1)
				(type solid)
			)
			(layer "F.SilkS")
		)
		(fp_line
			(start -0.094672 0.001008)
			(end 0.105328 -0.198992)
			(stroke
				(width 0.1)
				(type solid)
			)
			(layer "F.SilkS")
		)
		(fp_line
			(start 0.105328 0.001008)
			(end 0.24 0.001)
			(stroke
				(width 0.1)
				(type solid)
			)
			(layer "F.SilkS")
		)
		(fp_line
			(start -1.18 -0.319)
			(end -1.18 0.321)
			(stroke
				(width 0.15)
				(type solid)
			)
			(layer "F.SilkS")
		)
		(fp_line
			(start 0.22 -0.35)
			(end -0.22 -0.35)
			(stroke
				(width 0.15)
				(type solid)
			)
			(layer "F.SilkS")
		)
		(fp_rect
			(start 1.25 0.65)
			(end -1.25 -0.65)
			(stroke
				(width 0.05)
				(type solid)
			)
			(fill no)
			(layer "F.CrtYd")
		)
		(fp_line
			(start -0.199 0.2)
			(end -0.199 0.1)
			(stroke
				(width 0.15)
				(type solid)
			)
			(layer "F.Fab")
		)
		(fp_line
			(start 0.201 0.2)
			(end 0.201 0)
			(stroke
				(width 0.15)
				(type solid)
			)
			(layer "F.Fab")
		)
		(fp_line
			(start -0.199 0)
			(end -0.597 0)
			(stroke
				(width 0.15)
				(type solid)
			)
			(layer "F.Fab")
		)
		(fp_line
			(start -0.101 0)
			(end 0.201 0.2)
			(stroke
				(width 0.15)
				(type solid)
			)
			(layer "F.Fab")
		)
		(fp_line
			(start 0.201 0)
			(end 0.201 -0.202)
			(stroke
				(width 0.15)
				(type solid)
			)
			(layer "F.Fab")
		)
		(fp_line
			(start 0.599 0)
			(end 0.201 0)
			(stroke
				(width 0.15)
				(type solid)
			)
			(layer "F.Fab")
		)
		(fp_line
			(start -0.199 -0.202)
			(end -0.199 0.1)
			(stroke
				(width 0.15)
				(type solid)
			)
			(layer "F.Fab")
		)
		(fp_line
			(start 0.201 -0.202)
			(end -0.101 0)
			(stroke
				(width 0.15)
				(type solid)
			)
			(layer "F.Fab")
		)
		(fp_rect
			(start 0.848 0.4)
			(end -0.85 -0.402)
			(stroke
				(width 0.15)
				(type solid)
			)
			(fill no)
			(layer "F.Fab")
		)
		(fp_text user "Author: Antmicro"
			(at -1.4224 4.799 90)
			(layer "F.Fab")
			(effects
				(font
					(size 0.7 0.7)
					(thickness 0.15)
				)
				(justify right top)
			)
		)
		(fp_text user "${REFERENCE}"
			(at -1.4224 5.999 90)
			(layer "F.Fab")
			(effects
				(font
					(size 0.7 0.7)
					(thickness 0.15)
				)
				(justify right top)
			)
		)
		(fp_text user "License: Apache-2.0"
			(at -1.4224 3.599 90)
			(layer "F.Fab")
			(effects
				(font
					(size 0.7 0.7)
					(thickness 0.15)
				)
				(justify right top)
			)
		)
		(pad "1" smd roundrect
			(at -0.7 0 90)
			(size 0.8 1)
			(layers "F.Cu" "F.Mask" "F.Paste")
			(roundrect_rratio 0.2)
			(net 891 "Net-(D40-C)")
			(pinfunction "C")
			(pintype "passive")
		)
		(pad "2" smd roundrect
			(at 0.7 0 90)
			(size 0.8 1)
			(layers "F.Cu" "F.Mask" "F.Paste")
			(roundrect_rratio 0.2)
			(net 1008 "Net-(D40-A)")
			(pinfunction "A")
			(pintype "passive")
		)
	)
	(footprint "antmicro-footprints:TP_SMD_0.75mm"
		(layer "F.Cu")
		(at 82.1 128.5 180)
		(property "Reference" "TP72"
			(at 0.5 0.5 180)
			(layer "F.SilkS")
			(effects
				(font
					(size 0.7 0.7)
					(thickness 0.15)
				)
				(justify left bottom)
			)
		)
		(property "Value" "TP_0.75mm_SMD"
			(at 0 1.2 180)
			(layer "F.Fab")
			(effects
				(font
					(size 0.7 0.7)
					(thickness 0.15)
				)
				(justify left bottom)
			)
		)
		(property "Description" "SMT test point"
			(at 0 0 180)
			(layer "F.Fab")
			(hide yes)
			(effects
				(font
					(size 1.27 1.27)
					(thickness 0.15)
				)
			)
		)
		(property "MPN" ""
			(at 0 0 180)
			(unlocked yes)
			(layer "F.Fab")
			(hide yes)
			(effects
				(font
					(size 1 1)
					(thickness 0.15)
				)
			)
		)
		(property "Manufacturer" ""
			(at 0 0 180)
			(unlocked yes)
			(layer "F.Fab")
			(hide yes)
			(effects
				(font
					(size 1 1)
					(thickness 0.15)
				)
			)
		)
		(property "Author" "Antmicro"
			(at 0 0 180)
			(unlocked yes)
			(layer "F.Fab")
			(hide yes)
			(effects
				(font
					(size 1 1)
					(thickness 0.15)
				)
			)
		)
		(property "License" "Apache-2.0"
			(at 0 0 180)
			(unlocked yes)
			(layer "F.Fab")
			(hide yes)
			(effects
				(font
					(size 1 1)
					(thickness 0.15)
				)
			)
		)
		(sheetname "/Expansion connector/")
		(sheetfile "expansion_connector.kicad_sch")
		(attr exclude_from_pos_files exclude_from_bom)
		(fp_circle
			(center 0 0)
			(end 0.475 0)
			(stroke
				(width 0.05)
				(type default)
			)
			(fill no)
			(layer "F.CrtYd")
		)
		(fp_text user "${REFERENCE}"
			(at -0.4 2.7 180)
			(layer "F.Fab")
			(effects
				(font
					(size 0.7 0.7)
					(thickness 0.15)
				)
				(justify left bottom)
			)
		)
		(fp_text user "Author: Antmicro"
			(at -0.4 3.901 180)
			(layer "F.Fab")
			(effects
				(font
					(size 0.7 0.7)
					(thickness 0.15)
				)
				(justify left bottom)
			)
		)
		(fp_text user "License: Apache-2.0"
			(at -0.4 5.101 180)
			(layer "F.Fab")
			(effects
				(font
					(size 0.7 0.7)
					(thickness 0.15)
				)
				(justify left bottom)
			)
		)
		(pad "1" smd circle
			(at 0 0 180)
			(size 0.75 0.75)
			(layers "F.Cu" "F.Mask")
			(net 777 "Net-(J18-PadB40)")
			(pinfunction "1")
			(pintype "passive")
		)
	)
)
